(kicad_pcb
	(version 20241229)
	(generator "pcbnew")
	(generator_version "9.0")
	(general
		(thickness 1.61)
		(legacy_teardrops no)
	)
	(paper "A3")
	(title_block
		(title "SO-DIMM DDR5 Tester")
		(date "2025-11-26")
		(rev "1.3.0")
		(comment 9 "footprint 59 of 627 (U4), pads 426-500 of 676")
	)
	(layers
		(0 "F.Cu" signal)
		(4 "In1.Cu" power)
		(6 "In2.Cu" mixed)
		(8 "In3.Cu" power)
		(10 "In4.Cu" mixed)
		(12 "In5.Cu" power)
		(14 "In6.Cu" mixed)
		(16 "In7.Cu" power)
		(18 "In8.Cu" power)
		(20 "In9.Cu" mixed)
		(22 "In10.Cu" power)
		(2 "B.Cu" signal)
		(9 "F.Adhes" user "F.Adhesive")
		(11 "B.Adhes" user "B.Adhesive")
		(13 "F.Paste" user)
		(15 "B.Paste" user)
		(5 "F.SilkS" user "F.Silkscreen")
		(7 "B.SilkS" user "B.Silkscreen")
		(1 "F.Mask" user)
		(3 "B.Mask" user)
		(17 "Dwgs.User" user "User.Drawings")
		(19 "Cmts.User" user "User.Comments")
		(21 "Eco1.User" user "User.Eco1")
		(23 "Eco2.User" user "User.Eco2")
		(25 "Edge.Cuts" user)
		(27 "Margin" user)
		(31 "F.CrtYd" user "F.Courtyard")
		(29 "B.CrtYd" user "B.Courtyard")
		(35 "F.Fab" user)
		(33 "B.Fab" user)
	)
	(footprint "antmicro-footprints:BGA-676_27x27mm_Layout26x26_P1x1mm_FFG676"
		(layer "F.Cu")
		(at 138.875501 174.801 180)
		(descr "FPGA XC7K160TFBG676")
		(tags "FPGA XC7K160TFBG676")
		(property "Reference" "U4"
			(at -12.224499 14.051 180)
			(layer "F.SilkS")
			(effects
				(font
					(size 0.7 0.7)
					(thickness 0.15)
				)
				(justify left bottom)
			)
		)
		(property "Value" "XC7K160T-FFG676"
			(at 0 15.5 180)
			(layer "F.Fab")
			(effects
				(font
					(size 0.7 0.7)
					(thickness 0.15)
				)
				(justify left bottom)
			)
		)
		(property "Datasheet" "https://docs.xilinx.com/v/u/en-US/ds180_7Series_Overview"
			(at 0 0 180)
			(layer "F.Fab")
			(hide yes)
			(effects
				(font
					(size 1.27 1.27)
					(thickness 0.15)
				)
			)
		)
		(property "Author" "Antmicro"
			(at 277.751002 349.602 0)
			(layer "F.Fab")
			(hide yes)
			(effects
				(font
					(size 1 1)
					(thickness 0.15)
				)
			)
		)
		(property "License" "Apache-2.0"
			(at 277.751002 349.602 0)
			(layer "F.Fab")
			(hide yes)
			(effects
				(font
					(size 1 1)
					(thickness 0.15)
				)
			)
		)
		(property "MPN" "XC7K160T-FFG676"
			(at 277.751002 349.602 0)
			(layer "F.Fab")
			(hide yes)
			(effects
				(font
					(size 1 1)
					(thickness 0.15)
				)
			)
		)
		(property "Manufacturer" "AMD-Xilinx"
			(at 277.751002 349.602 0)
			(layer "F.Fab")
			(hide yes)
			(effects
				(font
					(size 1 1)
					(thickness 0.15)
				)
			)
		)
		(sheetname "/FPGA Config/")
		(sheetfile "fpga-config.kicad_sch")
		(attr smd)
		(pad "L10" smd circle
			(at -3.5 -2.5 180)
			(size 0.5 0.5)
			(layers "F.Cu" "F.Mask" "F.Paste")
			(net 1 "GND")
			(pinfunction "GND")
			(pintype "passive")
		)
		(pad "L11" smd circle
			(at -2.5 -2.5 180)
			(size 0.5 0.5)
			(layers "F.Cu" "F.Mask" "F.Paste")
			(net 188 "+1V8")
			(pinfunction "VCCAUX")
			(pintype "power_in")
		)
		(pad "L12" smd circle
			(at -1.5 -2.5 180)
			(size 0.5 0.5)
			(layers "F.Cu" "F.Mask" "F.Paste")
			(net 1 "GND")
			(pinfunction "GND")
			(pintype "passive")
		)
		(pad "L13" smd circle
			(at -0.5 -2.5 180)
			(size 0.5 0.5)
			(layers "F.Cu" "F.Mask" "F.Paste")
			(net 227 "+1V0")
			(pinfunction "VCCINT")
			(pintype "passive")
		)
		(pad "L14" smd circle
			(at 0.499 -2.5 180)
			(size 0.5 0.5)
			(layers "F.Cu" "F.Mask" "F.Paste")
			(net 1 "GND")
			(pinfunction "GND")
			(pintype "passive")
		)
		(pad "L15" smd circle
			(at 1.499 -2.5 180)
			(size 0.5 0.5)
			(layers "F.Cu" "F.Mask" "F.Paste")
			(net 227 "+1V0")
			(pinfunction "VCCINT")
			(pintype "passive")
		)
		(pad "L16" smd circle
			(at 2.499 -2.5 180)
			(size 0.5 0.5)
			(layers "F.Cu" "F.Mask" "F.Paste")
			(net 1 "GND")
			(pinfunction "GND")
			(pintype "passive")
		)
		(pad "L17" smd circle
			(at 3.499 -2.5 180)
			(size 0.5 0.5)
			(layers "F.Cu" "F.Mask" "F.Paste")
			(net 506 "unconnected-(U4D-IO_L24P_T3_RS1_15-PadL17)")
			(pinfunction "IO_L24P_T3_RS1_15")
			(pintype "bidirectional+no_connect")
			(die_length 6.318)
		)
		(pad "L18" smd circle
			(at 4.499 -2.5 180)
			(size 0.5 0.5)
			(layers "F.Cu" "F.Mask" "F.Paste")
			(net 507 "unconnected-(U4D-IO_L23N_T3_FWE_B_15-PadL18)")
			(pinfunction "IO_L23N_T3_FWE_B_15")
			(pintype "bidirectional+no_connect")
			(die_length 7.658)
		)
		(pad "L19" smd circle
			(at 5.499 -2.5 180)
			(size 0.5 0.5)
			(layers "F.Cu" "F.Mask" "F.Paste")
			(net 508 "unconnected-(U4D-IO_L21P_T3_DQS_15-PadL19)")
			(pinfunction "IO_L21P_T3_DQS_15")
			(pintype "bidirectional+no_connect")
			(die_length 7.664)
		)
		(pad "L20" smd circle
			(at 6.499 -2.5 180)
			(size 0.5 0.5)
			(layers "F.Cu" "F.Mask" "F.Paste")
			(net 509 "unconnected-(U4D-IO_L21N_T3_DQS_A18_15-PadL20)")
			(pinfunction "IO_L21N_T3_DQS_A18_15")
			(pintype "bidirectional+no_connect")
			(die_length 7.681)
		)
		(pad "L21" smd circle
			(at 7.499 -2.5 180)
			(size 0.5 0.5)
			(layers "F.Cu" "F.Mask" "F.Paste")
			(net 200 "+3V3")
			(pinfunction "VCCO_14")
			(pintype "passive")
		)
		(pad "L22" smd circle
			(at 8.499 -2.5 180)
			(size 0.5 0.5)
			(layers "F.Cu" "F.Mask" "F.Paste")
			(net 510 "unconnected-(U4C-IO_L23P_T3_A03_D19_14-PadL22)")
			(pinfunction "IO_L23P_T3_A03_D19_14")
			(pintype "bidirectional+no_connect")
			(die_length 16.198)
		)
		(pad "L23" smd circle
			(at 9.499 -2.5 180)
			(size 0.5 0.5)
			(layers "F.Cu" "F.Mask" "F.Paste")
			(net 511 "unconnected-(U4C-IO_25_14-PadL23)")
			(pinfunction "IO_25_14")
			(pintype "bidirectional+no_connect")
			(die_length 15.436)
		)
		(pad "L24" smd circle
			(at 10.499 -2.5 180)
			(size 0.5 0.5)
			(layers "F.Cu" "F.Mask" "F.Paste")
			(net 512 "unconnected-(U4B-IO_L8N_T1_13-PadL24)")
			(pinfunction "IO_L8N_T1_13")
			(pintype "bidirectional+no_connect")
			(die_length 16.877)
		)
		(pad "L25" smd circle
			(at 11.499 -2.5 180)
			(size 0.5 0.5)
			(layers "F.Cu" "F.Mask" "F.Paste")
			(net 513 "unconnected-(U4B-IO_L3N_T0_DQS_13-PadL25)")
			(pinfunction "IO_L3N_T0_DQS_13")
			(pintype "bidirectional+no_connect")
			(die_length 16.692)
		)
		(pad "L26" smd circle
			(at 12.499 -2.5 180)
			(size 0.5 0.5)
			(layers "F.Cu" "F.Mask" "F.Paste")
			(net 1 "GND")
			(pinfunction "GND")
			(pintype "passive")
		)
		(pad "M1" smd circle
			(at -12.5 -1.5 180)
			(size 0.5 0.5)
			(layers "F.Cu" "F.Mask" "F.Paste")
			(net 514 "unconnected-(U4I-MGTXTXN1_115-PadM1)")
			(pinfunction "MGTXTXN1_115")
			(pintype "bidirectional+no_connect")
			(die_length 13.445)
		)
		(pad "M2" smd circle
			(at -11.5 -1.5 180)
			(size 0.5 0.5)
			(layers "F.Cu" "F.Mask" "F.Paste")
			(net 515 "unconnected-(U4I-MGTXTXP1_115-PadM2)")
			(pinfunction "MGTXTXP1_115")
			(pintype "bidirectional+no_connect")
			(die_length 13.639)
		)
		(pad "M3" smd circle
			(at -10.5 -1.5 180)
			(size 0.5 0.5)
			(layers "F.Cu" "F.Mask" "F.Paste")
			(net 226 "+1V2_MGTAVTT")
			(pinfunction "MGTAVTT")
			(pintype "passive")
		)
		(pad "M4" smd circle
			(at -9.5 -1.5 180)
			(size 0.5 0.5)
			(layers "F.Cu" "F.Mask" "F.Paste")
			(net 1 "GND")
			(pinfunction "GND")
			(pintype "passive")
		)
		(pad "M5" smd circle
			(at -8.5 -1.5 180)
			(size 0.5 0.5)
			(layers "F.Cu" "F.Mask" "F.Paste")
			(net 226 "+1V2_MGTAVTT")
			(pinfunction "MGTAVTTRCAL_115")
			(pintype "power_in")
		)
		(pad "M6" smd circle
			(at -7.5 -1.5 180)
			(size 0.5 0.5)
			(layers "F.Cu" "F.Mask" "F.Paste")
			(net 369 "Net-(U4J-MGTRREF_115)")
			(pinfunction "MGTRREF_115")
			(pintype "power_in")
			(die_length 11.045)
		)
		(pad "M7" smd circle
			(at -6.5 -1.5 180)
			(size 0.5 0.5)
			(layers "F.Cu" "F.Mask" "F.Paste")
			(net 1 "GND")
			(pinfunction "GND")
			(pintype "passive")
		)
		(pad "M8" smd circle
			(at -5.5 -1.5 180)
			(size 0.5 0.5)
			(layers "F.Cu" "F.Mask" "F.Paste")
			(net 227 "+1V0")
			(pinfunction "VCCINT")
			(pintype "passive")
		)
		(pad "M9" smd circle
			(at -4.5 -1.5 180)
			(size 0.5 0.5)
			(layers "F.Cu" "F.Mask" "F.Paste")
			(net 1 "GND")
			(pinfunction "GND")
			(pintype "passive")
		)
		(pad "M10" smd circle
			(at -3.5 -1.5 180)
			(size 0.5 0.5)
			(layers "F.Cu" "F.Mask" "F.Paste")
			(net 188 "+1V8")
			(pinfunction "VCCAUX")
			(pintype "passive")
		)
		(pad "M11" smd circle
			(at -2.5 -1.5 180)
			(size 0.5 0.5)
			(layers "F.Cu" "F.Mask" "F.Paste")
			(net 1 "GND")
			(pinfunction "GNDADC_0")
			(pintype "power_in")
		)
		(pad "M12" smd circle
			(at -1.5 -1.5 180)
			(size 0.5 0.5)
			(layers "F.Cu" "F.Mask" "F.Paste")
			(net 188 "+1V8")
			(pinfunction "VCCADC_0")
			(pintype "power_in")
		)
		(pad "M13" smd circle
			(at -0.5 -1.5 180)
			(size 0.5 0.5)
			(layers "F.Cu" "F.Mask" "F.Paste")
			(net 1 "GND")
			(pinfunction "GND")
			(pintype "passive")
		)
		(pad "M14" smd circle
			(at 0.499 -1.5 180)
			(size 0.5 0.5)
			(layers "F.Cu" "F.Mask" "F.Paste")
			(net 227 "+1V0")
			(pinfunction "VCCINT")
			(pintype "passive")
		)
		(pad "M15" smd circle
			(at 1.499 -1.5 180)
			(size 0.5 0.5)
			(layers "F.Cu" "F.Mask" "F.Paste")
			(net 1 "GND")
			(pinfunction "GND")
			(pintype "passive")
		)
		(pad "M16" smd circle
			(at 2.499 -1.5 180)
			(size 0.5 0.5)
			(layers "F.Cu" "F.Mask" "F.Paste")
			(net 516 "unconnected-(U4D-IO_25_15-PadM16)")
			(pinfunction "IO_25_15")
			(pintype "bidirectional+no_connect")
			(die_length 5.552)
		)
		(pad "M17" smd circle
			(at 3.499 -1.5 180)
			(size 0.5 0.5)
			(layers "F.Cu" "F.Mask" "F.Paste")
			(net 517 "unconnected-(U4D-IO_L23P_T3_FOE_B_15-PadM17)")
			(pinfunction "IO_L23P_T3_FOE_B_15")
			(pintype "bidirectional+no_connect")
			(die_length 8.087)
		)
		(pad "M18" smd circle
			(at 4.499 -1.5 180)
			(size 0.5 0.5)
			(layers "F.Cu" "F.Mask" "F.Paste")
			(net 377 "Net-(R97-Pad2)")
			(pinfunction "VCCO_15")
			(pintype "passive")
		)
		(pad "M19" smd circle
			(at 5.499 -1.5 180)
			(size 0.5 0.5)
			(layers "F.Cu" "F.Mask" "F.Paste")
			(net 518 "unconnected-(U4B-IO_L22N_T3_13-PadM19)")
			(pinfunction "IO_L22N_T3_13")
			(pintype "bidirectional+no_connect")
			(die_length 14.527)
		)
		(pad "M20" smd circle
			(at 6.499 -1.5 180)
			(size 0.5 0.5)
			(layers "F.Cu" "F.Mask" "F.Paste")
			(net 519 "unconnected-(U4B-IO_L7N_T1_13-PadM20)")
			(pinfunction "IO_L7N_T1_13")
			(pintype "bidirectional+no_connect")
			(die_length 12.084)
		)
		(pad "M21" smd circle
			(at 7.499 -1.5 180)
			(size 0.5 0.5)
			(layers "F.Cu" "F.Mask" "F.Paste")
			(net 520 "unconnected-(U4B-IO_L10P_T1_13-PadM21)")
			(pinfunction "IO_L10P_T1_13")
			(pintype "bidirectional+no_connect")
			(die_length 14.496)
		)
		(pad "M22" smd circle
			(at 8.499 -1.5 180)
			(size 0.5 0.5)
			(layers "F.Cu" "F.Mask" "F.Paste")
			(net 521 "unconnected-(U4B-IO_L10N_T1_13-PadM22)")
			(pinfunction "IO_L10N_T1_13")
			(pintype "bidirectional+no_connect")
			(die_length 14.558)
		)
		(pad "M23" smd circle
			(at 9.499 -1.5 180)
			(size 0.5 0.5)
			(layers "F.Cu" "F.Mask" "F.Paste")
			(net 1 "GND")
			(pinfunction "GND")
			(pintype "passive")
		)
		(pad "M24" smd circle
			(at 10.499 -1.5 180)
			(size 0.5 0.5)
			(layers "F.Cu" "F.Mask" "F.Paste")
			(net 522 "unconnected-(U4B-IO_L8P_T1_13-PadM24)")
			(pinfunction "IO_L8P_T1_13")
			(pintype "bidirectional+no_connect")
			(die_length 15.433)
		)
		(pad "M25" smd circle
			(at 11.499 -1.5 180)
			(size 0.5 0.5)
			(layers "F.Cu" "F.Mask" "F.Paste")
			(net 523 "unconnected-(U4B-IO_L3P_T0_DQS_13-PadM25)")
			(pinfunction "IO_L3P_T0_DQS_13")
			(pintype "bidirectional+no_connect")
			(die_length 16.172)
		)
		(pad "M26" smd circle
			(at 12.499 -1.5 180)
			(size 0.5 0.5)
			(layers "F.Cu" "F.Mask" "F.Paste")
			(net 524 "unconnected-(U4B-IO_L5N_T0_13-PadM26)")
			(pinfunction "IO_L5N_T0_13")
			(pintype "bidirectional+no_connect")
			(die_length 16.457)
		)
		(pad "N1" smd circle
			(at -12.5 -0.5 180)
			(size 0.5 0.5)
			(layers "F.Cu" "F.Mask" "F.Paste")
			(net 1 "GND")
			(pinfunction "GND")
			(pintype "passive")
		)
		(pad "N2" smd circle
			(at -11.5 -0.5 180)
			(size 0.5 0.5)
			(layers "F.Cu" "F.Mask" "F.Paste")
			(net 1 "GND")
			(pinfunction "GND")
			(pintype "passive")
		)
		(pad "N3" smd circle
			(at -10.5 -0.5 180)
			(size 0.5 0.5)
			(layers "F.Cu" "F.Mask" "F.Paste")
			(net 525 "unconnected-(U4I-MGTXRXN1_115-PadN3)")
			(pinfunction "MGTXRXN1_115")
			(pintype "bidirectional+no_connect")
			(die_length 12.774)
		)
		(pad "N4" smd circle
			(at -9.5 -0.5 180)
			(size 0.5 0.5)
			(layers "F.Cu" "F.Mask" "F.Paste")
			(net 526 "unconnected-(U4I-MGTXRXP1_115-PadN4)")
			(pinfunction "MGTXRXP1_115")
			(pintype "bidirectional+no_connect")
			(die_length 12.878)
		)
		(pad "N5" smd circle
			(at -8.5 -0.5 180)
			(size 0.5 0.5)
			(layers "F.Cu" "F.Mask" "F.Paste")
			(net 1 "GND")
			(pinfunction "GND")
			(pintype "passive")
		)
		(pad "N6" smd circle
			(at -7.5 -0.5 180)
			(size 0.5 0.5)
			(layers "F.Cu" "F.Mask" "F.Paste")
			(net 188 "+1V8")
			(pinfunction "MGTVCCAUX")
			(pintype "power_in")
		)
		(pad "N7" smd circle
			(at -6.5 -0.5 180)
			(size 0.5 0.5)
			(layers "F.Cu" "F.Mask" "F.Paste")
			(net 1 "GND")
			(pinfunction "GND")
			(pintype "passive")
		)
		(pad "N8" smd circle
			(at -5.5 -0.5 180)
			(size 0.5 0.5)
			(layers "F.Cu" "F.Mask" "F.Paste")
			(net 45 "/Debug FTDI/JTAG.TMS")
			(pinfunction "TMS_0")
			(pintype "bidirectional")
			(die_length 12.891)
		)
		(pad "N9" smd circle
			(at -4.5 -0.5 180)
			(size 0.5 0.5)
			(layers "F.Cu" "F.Mask" "F.Paste")
			(net 227 "+1V0")
			(pinfunction "VCCINT")
			(pintype "passive")
		)
		(pad "N10" smd circle
			(at -3.5 -0.5 180)
			(size 0.5 0.5)
			(layers "F.Cu" "F.Mask" "F.Paste")
			(net 1 "GND")
			(pinfunction "GND")
			(pintype "passive")
		)
		(pad "N11" smd circle
			(at -2.5 -0.5 180)
			(size 0.5 0.5)
			(layers "F.Cu" "F.Mask" "F.Paste")
			(net 1 "GND")
			(pinfunction "VREFN_0")
			(pintype "bidirectional")
			(die_length 14.753)
		)
		(pad "N12" smd circle
			(at -1.5 -0.5 180)
			(size 0.5 0.5)
			(layers "F.Cu" "F.Mask" "F.Paste")
			(net 1 "GND")
			(pinfunction "VP_0")
			(pintype "bidirectional")
			(die_length 12.915)
		)
		(pad "N13" smd circle
			(at -0.5 -0.5 180)
			(size 0.5 0.5)
			(layers "F.Cu" "F.Mask" "F.Paste")
			(net 227 "+1V0")
			(pinfunction "VCCBRAM")
			(pintype "power_in")
		)
		(pad "N14" smd circle
			(at 0.499 -0.5 180)
			(size 0.5 0.5)
			(layers "F.Cu" "F.Mask" "F.Paste")
			(net 1 "GND")
			(pinfunction "GND")
			(pintype "passive")
		)
		(pad "N15" smd circle
			(at 1.499 -0.5 180)
			(size 0.5 0.5)
			(layers "F.Cu" "F.Mask" "F.Paste")
			(net 227 "+1V0")
			(pinfunction "VCCINT")
			(pintype "passive")
		)
		(pad "N16" smd circle
			(at 2.499 -0.5 180)
			(size 0.5 0.5)
			(layers "F.Cu" "F.Mask" "F.Paste")
			(net 527 "unconnected-(U4B-IO_0_13-PadN16)")
			(pinfunction "IO_0_13")
			(pintype "bidirectional+no_connect")
			(die_length 6.733)
		)
		(pad "N17" smd circle
			(at 3.499 -0.5 180)
			(size 0.5 0.5)
			(layers "F.Cu" "F.Mask" "F.Paste")
			(net 528 "unconnected-(U4B-IO_L20N_T3_13-PadN17)")
			(pinfunction "IO_L20N_T3_13")
			(pintype "bidirectional+no_connect")
			(die_length 9.445)
		)
		(pad "N18" smd circle
			(at 4.499 -0.5 180)
			(size 0.5 0.5)
			(layers "F.Cu" "F.Mask" "F.Paste")
			(net 529 "unconnected-(U4B-IO_L22P_T3_13-PadN18)")
			(pinfunction "IO_L22P_T3_13")
			(pintype "bidirectional+no_connect")
			(die_length 11.191)
		)
		(pad "N19" smd circle
			(at 5.499 -0.5 180)
			(size 0.5 0.5)
			(layers "F.Cu" "F.Mask" "F.Paste")
			(net 530 "unconnected-(U4B-IO_L7P_T1_13-PadN19)")
			(pinfunction "IO_L7P_T1_13")
			(pintype "bidirectional+no_connect")
			(die_length 10.696)
		)
		(pad "N20" smd circle
			(at 6.499 -0.5 180)
			(size 0.5 0.5)
			(layers "F.Cu" "F.Mask" "F.Paste")
			(net 1 "GND")
			(pinfunction "GND")
			(pintype "passive")
		)
		(pad "N21" smd circle
			(at 7.499 -0.5 180)
			(size 0.5 0.5)
			(layers "F.Cu" "F.Mask" "F.Paste")
			(net 531 "unconnected-(U4B-IO_L12P_T1_MRCC_13-PadN21)")
			(pinfunction "IO_L12P_T1_MRCC_13")
			(pintype "bidirectional+no_connect")
			(die_length 11.848)
		)
		(pad "N22" smd circle
			(at 8.499 -0.5 180)
			(size 0.5 0.5)
			(layers "F.Cu" "F.Mask" "F.Paste")
			(net 532 "unconnected-(U4B-IO_L12N_T1_MRCC_13-PadN22)")
			(pinfunction "IO_L12N_T1_MRCC_13")
			(pintype "bidirectional+no_connect")
			(die_length 12.32)
		)
		(pad "N23" smd circle
			(at 9.499 -0.5 180)
			(size 0.5 0.5)
			(layers "F.Cu" "F.Mask" "F.Paste")
			(net 533 "unconnected-(U4B-IO_L11N_T1_SRCC_13-PadN23)")
			(pinfunction "IO_L11N_T1_SRCC_13")
			(pintype "bidirectional+no_connect")
			(die_length 14.434)
		)
		(pad "N24" smd circle
			(at 10.499 -0.5 180)
			(size 0.5 0.5)
			(layers "F.Cu" "F.Mask" "F.Paste")
			(net 534 "unconnected-(U4B-IO_L4N_T0_13-PadN24)")
			(pinfunction "IO_L4N_T0_13")
			(pintype "bidirectional+no_connect")
			(die_length 15.311)
		)
		(pad "N25" smd circle
			(at 11.499 -0.5 180)
			(size 0.5 0.5)
			(layers "F.Cu" "F.Mask" "F.Paste")
			(net 376 "Net-(R96-Pad2)")
			(pinfunction "VCCO_13")
			(pintype "passive")
		)
		(pad "N26" smd circle
			(at 12.499 -0.5 180)
			(size 0.5 0.5)
			(layers "F.Cu" "F.Mask" "F.Paste")
			(net 535 "unconnected-(U4B-IO_L5P_T0_13-PadN26)")
			(pinfunction "IO_L5P_T0_13")
			(pintype "bidirectional+no_connect")
			(die_length 16.049)
		)
		(pad "P1" smd circle
			(at -12.5 0.499 180)
			(size 0.5 0.5)
			(layers "F.Cu" "F.Mask" "F.Paste")
			(net 536 "unconnected-(U4I-MGTXTXN0_115-PadP1)")
			(pinfunction "MGTXTXN0_115")
			(pintype "bidirectional+no_connect")
			(die_length 14.843)
		)
		(pad "P2" smd circle
			(at -11.5 0.499 180)
			(size 0.5 0.5)
			(layers "F.Cu" "F.Mask" "F.Paste")
			(net 537 "unconnected-(U4I-MGTXTXP0_115-PadP2)")
			(pinfunction "MGTXTXP0_115")
			(pintype "bidirectional+no_connect")
			(die_length 15.009)
		)
		(pad "P3" smd circle
			(at -10.5 0.499 180)
			(size 0.5 0.5)
			(layers "F.Cu" "F.Mask" "F.Paste")
			(net 1 "GND")
			(pinfunction "GND")
			(pintype "passive")
		)
		(pad "P4" smd circle
			(at -9.5 0.499 180)
			(size 0.5 0.5)
			(layers "F.Cu" "F.Mask" "F.Paste")
			(net 1 "GND")
			(pinfunction "GND")
			(pintype "passive")
		)
		(pad "P5" smd circle
			(at -8.5 0.499 180)
			(size 0.5 0.5)
			(layers "F.Cu" "F.Mask" "F.Paste")
			(net 631 "/FPGA Config/MODE2")
			(pinfunction "M2_0")
			(pintype "bidirectional")
			(die_length 16.743)
		)
		(pad "P6" smd circle
			(at -7.5 0.499 180)
			(size 0.5 0.5)
			(layers "F.Cu" "F.Mask" "F.Paste")
			(net 634 "/FPGA Config/PROGRAM_B")
			(pinfunction "PROGRAM_B_0")
			(pintype "bidirectional")
			(die_length 16.276)
		)
	)
)
